# S9S_MB_2U (Grand Teton) — schematic netlist excerpt (pin names and nets, part order shuffled) for the footprints in the layout excerpt that follows; sources: Cadence DE-HDL packaged netlist, KiCad conversion of 03242023_DA0F0TMBIJ0_F0T_Motherboard_J_brd_V01_OCP.brd

C883  Q_CAP_DIFFBUS  DIFF BUS_0.22UF 6.3V 20% X6S  pkg C0201  page 174 : \1\ = P5E_CPU0_PE3_TX_C_DP<9> ; \2\ = P5E_CPU0_PE3_TX_DP<9>
PC1651  Q_CAP  100NF 50V 10% X7R  pkg C0402  page 263 : A = P12V_AUX ; B = GND
C1841  Q_CAP  0.1UF 25V 10% X7R  pkg 0402  page 161 : A = P3V3_AUX ; B = GND
ME21  ME_DUMMY_SYMBOL  PCB_VENDOR_LOGO_15X8 EMPTY  pkg PCB_VENDOR_LOGO_15X8  page 312

(kicad_pcb
	(version 20260206)
	(generator "pcbnew")
	(generator_version "10.0")
	(general
		(thickness 1.6)
		(legacy_teardrops no)
	)
	(paper "A4")
	(title_block
		(title "03242023_DA0F0TMBIJ0_F0T_Motherboard_J_brd_V01_OCP.brd")
		(comment 1 "Grand Teton / footprints 2831-2834 of 6105")
	)
	(layers
		(0 "F.Cu" signal "TOP")
		(4 "In1.Cu" signal "GND")
		(6 "In2.Cu" signal "IN1")
		(8 "In3.Cu" signal "GND1")
		(10 "In4.Cu" signal "IN2")
		(12 "In5.Cu" signal "GND2")
		(14 "In6.Cu" signal "IN3")
		(16 "In7.Cu" signal "GND3")
		(18 "In8.Cu" signal "VCC")
		(20 "In9.Cu" signal "VCC1")
		(22 "In10.Cu" signal "GND4")
		(24 "In11.Cu" signal "IN4")
		(26 "In12.Cu" signal "GND5")
		(28 "In13.Cu" signal "IN5")
		(30 "In14.Cu" signal "GND6")
		(32 "In15.Cu" signal "IN6")
		(34 "In16.Cu" signal "GND7")
		(2 "B.Cu" signal "BOTTOM")
		(9 "F.Adhes" user "F.Adhesive")
		(11 "B.Adhes" user "B.Adhesive")
		(13 "F.Paste" user "Package Geometry/Pastemask Top")
		(15 "B.Paste" user "Package Geometry/Pastemask Bottom")
		(5 "F.SilkS" user "Ref Des/Silkscreen Top")
		(7 "B.SilkS" user "Ref Des/Silkscreen Bottom")
		(1 "F.Mask" user "Board Geometry/Soldermask Top")
		(3 "B.Mask" user "Board Geometry/Soldermask Bottom")
		(17 "Dwgs.User" user "User.Drawings")
		(19 "Cmts.User" user "User.Comments")
		(21 "Eco1.User" user "User.Eco1")
		(23 "Eco2.User" user "User.Eco2")
		(25 "Edge.Cuts" user "Board Geometry/Outline")
		(27 "Margin" user)
		(31 "F.CrtYd" user "Package Geometry/Place Bound Top")
		(29 "B.CrtYd" user "Package Geometry/Place Bound Bottom")
		(35 "F.Fab" user "Ref Des/Assembly Top")
		(33 "B.Fab" user "Ref Des/Assembly Bottom")
	)
	(footprint ""
		(layer "F.Cu")
		(at 150.93188 -109.819948 -90)
		(property "Reference" "C1841"
			(at 0 0 270)
			(layer "F.SilkS")
			(hide yes)
			(effects
				(font
					(size 1.27 1.27)
				)
			)
		)
		(property "Value" ""
			(at 0 0 270)
			(layer "F.Fab")
			(effects
				(font
					(size 1.27 1.27)
				)
			)
		)
		(duplicate_pad_numbers_are_jumpers no)
		(fp_line
			(start -0.7874 0.4064)
			(end -0.7874 -0.4064)
			(stroke
				(width 0.1524)
				(type default)
			)
			(layer "F.SilkS")
		)
		(fp_line
			(start 0.7874 0.4064)
			(end -0.7874 0.4064)
			(stroke
				(width 0.1524)
				(type default)
			)
			(layer "F.SilkS")
		)
		(fp_line
			(start -0.7874 -0.4064)
			(end 0.7874 -0.4064)
			(stroke
				(width 0.1524)
				(type default)
			)
			(layer "F.SilkS")
		)
		(fp_line
			(start 0.7874 -0.4064)
			(end 0.7874 0.4064)
			(stroke
				(width 0.1524)
				(type default)
			)
			(layer "F.SilkS")
		)
		(fp_line
			(start -0.67945 0.3048)
			(end -0.67945 -0.305054)
			(stroke
				(width 0.1)
				(type default)
			)
			(layer "F.Fab")
		)
		(fp_line
			(start -0.12065 0.3048)
			(end -0.67945 0.3048)
			(stroke
				(width 0.1)
				(type default)
			)
			(layer "F.Fab")
		)
		(fp_line
			(start 0.120396 0.3048)
			(end 0.120396 0.2794)
			(stroke
				(width 0.1)
				(type default)
			)
			(layer "F.Fab")
		)
		(fp_line
			(start 0.67945 0.3048)
			(end 0.120396 0.3048)
			(stroke
				(width 0.1)
				(type default)
			)
			(layer "F.Fab")
		)
		(fp_line
			(start -0.12065 0.2794)
			(end -0.12065 0.3048)
			(stroke
				(width 0.1)
				(type default)
			)
			(layer "F.Fab")
		)
		(fp_line
			(start 0.120396 0.2794)
			(end -0.12065 0.2794)
			(stroke
				(width 0.1)
				(type default)
			)
			(layer "F.Fab")
		)
		(fp_line
			(start -0.12065 -0.2794)
			(end 0.12065 -0.2794)
			(stroke
				(width 0.1)
				(type default)
			)
			(layer "F.Fab")
		)
		(fp_line
			(start 0.12065 -0.2794)
			(end 0.12065 -0.3048)
			(stroke
				(width 0.1)
				(type default)
			)
			(layer "F.Fab")
		)
		(fp_line
			(start 0.12065 -0.3048)
			(end 0.67945 -0.3048)
			(stroke
				(width 0.1)
				(type default)
			)
			(layer "F.Fab")
		)
		(fp_line
			(start 0.67945 -0.3048)
			(end 0.67945 0.3048)
			(stroke
				(width 0.1)
				(type default)
			)
			(layer "F.Fab")
		)
		(fp_line
			(start -0.67945 -0.305054)
			(end -0.12065 -0.305054)
			(stroke
				(width 0.1)
				(type default)
			)
			(layer "F.Fab")
		)
		(fp_line
			(start -0.12065 -0.305054)
			(end -0.12065 -0.2794)
			(stroke
				(width 0.1)
				(type default)
			)
			(layer "F.Fab")
		)
		(pad "1" smd circle
			(at -0.40005 0 270)
			(size 0 0)
			(layers "F.Cu" "F.Mask" "F.Paste")
			(net "P3V3_AUX")
		)
		(pad "2" smd circle
			(at 0.40005 0 270)
			(size 0 0)
			(layers "F.Cu" "F.Mask" "F.Paste")
			(net "GND")
		)
	)
	(footprint ""
		(layer "F.Cu")
		(at 390.992106 -78.863698 180)
		(property "Reference" "PC1651"
			(at 0 0 180)
			(layer "F.SilkS")
			(hide yes)
			(effects
				(font
					(size 1.27 1.27)
				)
			)
		)
		(property "Value" ""
			(at 0 0 180)
			(layer "F.Fab")
			(effects
				(font
					(size 1.27 1.27)
				)
			)
		)
		(duplicate_pad_numbers_are_jumpers no)
		(fp_line
			(start 0.7874 0.4064)
			(end -0.7874 0.4064)
			(stroke
				(width 0.1524)
				(type default)
			)
			(layer "F.SilkS")
		)
		(fp_line
			(start 0.7874 -0.4064)
			(end 0.7874 0.4064)
			(stroke
				(width 0.1524)
				(type default)
			)
			(layer "F.SilkS")
		)
		(fp_line
			(start -0.7874 0.4064)
			(end -0.7874 -0.4064)
			(stroke
				(width 0.1524)
				(type default)
			)
			(layer "F.SilkS")
		)
		(fp_line
			(start -0.7874 -0.4064)
			(end 0.7874 -0.4064)
			(stroke
				(width 0.1524)
				(type default)
			)
			(layer "F.SilkS")
		)
		(fp_line
			(start 0.67945 0.3048)
			(end 0.120396 0.3048)
			(stroke
				(width 0.1)
				(type default)
			)
			(layer "F.Fab")
		)
		(fp_line
			(start 0.67945 -0.3048)
			(end 0.67945 0.3048)
			(stroke
				(width 0.1)
				(type default)
			)
			(layer "F.Fab")
		)
		(fp_line
			(start 0.12065 -0.2794)
			(end 0.12065 -0.3048)
			(stroke
				(width 0.1)
				(type default)
			)
			(layer "F.Fab")
		)
		(fp_line
			(start 0.12065 -0.3048)
			(end 0.67945 -0.3048)
			(stroke
				(width 0.1)
				(type default)
			)
			(layer "F.Fab")
		)
		(fp_line
			(start 0.120396 0.3048)
			(end 0.120396 0.2794)
			(stroke
				(width 0.1)
				(type default)
			)
			(layer "F.Fab")
		)
		(fp_line
			(start 0.120396 0.2794)
			(end -0.12065 0.2794)
			(stroke
				(width 0.1)
				(type default)
			)
			(layer "F.Fab")
		)
		(fp_line
			(start -0.12065 0.3048)
			(end -0.67945 0.3048)
			(stroke
				(width 0.1)
				(type default)
			)
			(layer "F.Fab")
		)
		(fp_line
			(start -0.12065 0.2794)
			(end -0.12065 0.3048)
			(stroke
				(width 0.1)
				(type default)
			)
			(layer "F.Fab")
		)
		(fp_line
			(start -0.12065 -0.2794)
			(end 0.12065 -0.2794)
			(stroke
				(width 0.1)
				(type default)
			)
			(layer "F.Fab")
		)
		(fp_line
			(start -0.12065 -0.305054)
			(end -0.12065 -0.2794)
			(stroke
				(width 0.1)
				(type default)
			)
			(layer "F.Fab")
		)
		(fp_line
			(start -0.67945 0.3048)
			(end -0.67945 -0.305054)
			(stroke
				(width 0.1)
				(type default)
			)
			(layer "F.Fab")
		)
		(fp_line
			(start -0.67945 -0.305054)
			(end -0.12065 -0.305054)
			(stroke
				(width 0.1)
				(type default)
			)
			(layer "F.Fab")
		)
		(pad "1" smd circle
			(at -0.40005 0 180)
			(size 0 0)
			(layers "F.Cu" "F.Mask" "F.Paste")
			(net "P12V_AUX")
		)
		(pad "2" smd circle
			(at 0.40005 0 180)
			(size 0 0)
			(layers "F.Cu" "F.Mask" "F.Paste")
			(net "GND")
		)
	)
	(footprint ""
		(layer "F.Cu")
		(at 228.31044 -365.940848)
		(property "Reference" "ME21"
			(at 0 0 0)
			(layer "F.SilkS")
			(hide yes)
			(effects
				(font
					(size 1.27 1.27)
				)
			)
		)
		(property "Value" ""
			(at 0 0 0)
			(layer "F.Fab")
			(effects
				(font
					(size 1.27 1.27)
				)
			)
		)
		(duplicate_pad_numbers_are_jumpers no)
	)
	(footprint ""
		(layer "F.Cu")
		(at 392.03757 -408.517344 -90)
		(property "Reference" "C883"
			(at 0 0 270)
			(layer "F.SilkS")
			(hide yes)
			(effects
				(font
					(size 1.27 1.27)
				)
			)
		)
		(property "Value" ""
			(at 0 0 270)
			(layer "F.Fab")
			(effects
				(font
					(size 1.27 1.27)
				)
			)
		)
		(duplicate_pad_numbers_are_jumpers no)
		(fp_line
			(start -0.299974 0.150114)
			(end -0.299974 -0.150114)
			(stroke
				(width 0.1)
				(type default)
			)
			(layer "F.Fab")
		)
		(fp_line
			(start 0.299974 0.150114)
			(end -0.299974 0.150114)
			(stroke
				(width 0.1)
				(type default)
			)
			(layer "F.Fab")
		)
		(fp_line
			(start -0.299974 -0.150114)
			(end 0.299974 -0.150114)
			(stroke
				(width 0.1)
				(type default)
			)
			(layer "F.Fab")
		)
		(fp_line
			(start 0.299974 -0.150114)
			(end 0.299974 0.150114)
			(stroke
				(width 0.1)
				(type default)
			)
			(layer "F.Fab")
		)
		(pad "1" smd rect
			(at -0.2667 0 270)
			(size 0.3048 0.381)
			(layers "F.Cu" "F.Mask" "F.Paste")
			(net "P5E_CPU0_PE3_TX_C_DP<9>")
		)
		(pad "2" smd rect
			(at 0.2667 0 270)
			(size 0.3048 0.381)
			(layers "F.Cu" "F.Mask" "F.Paste")
			(net "P5E_CPU0_PE3_TX_DP<9>")
		)
	)
)
